# S9S_MB_2U (Grand Teton) — schematic netlist excerpt (pin names and nets, part order shuffled) for the footprints in the layout excerpt that follows; sources: Cadence DE-HDL packaged netlist, KiCad conversion of 03242023_DA0F0TMBIJ0_F0T_Motherboard_J_brd_V01_OCP.brd

R483  Q_RES  0 5% CHIP  pkg 0402LF  page 239 : A = JTAG_BMC_DBP_TDO_R ; B = JTAG_BMC_DBP_TDO
R860  Q_RES  0 5% CHIP  pkg 0402LF  page 128 : A = RST_CPU1_DRAM_CD_N ; B = RST_CPU1_DRAM_CD_PLD_N

(kicad_pcb
	(version 20260206)
	(generator "pcbnew")
	(generator_version "10.0")
	(general
		(thickness 1.6)
		(legacy_teardrops no)
	)
	(paper "A4")
	(title_block
		(title "03242023_DA0F0TMBIJ0_F0T_Motherboard_J_brd_V01_OCP.brd")
		(comment 1 "Grand Teton / footprints 3295-3296 of 6105")
	)
	(layers
		(0 "F.Cu" signal "TOP")
		(4 "In1.Cu" signal "GND")
		(6 "In2.Cu" signal "IN1")
		(8 "In3.Cu" signal "GND1")
		(10 "In4.Cu" signal "IN2")
		(12 "In5.Cu" signal "GND2")
		(14 "In6.Cu" signal "IN3")
		(16 "In7.Cu" signal "GND3")
		(18 "In8.Cu" signal "VCC")
		(20 "In9.Cu" signal "VCC1")
		(22 "In10.Cu" signal "GND4")
		(24 "In11.Cu" signal "IN4")
		(26 "In12.Cu" signal "GND5")
		(28 "In13.Cu" signal "IN5")
		(30 "In14.Cu" signal "GND6")
		(32 "In15.Cu" signal "IN6")
		(34 "In16.Cu" signal "GND7")
		(2 "B.Cu" signal "BOTTOM")
		(9 "F.Adhes" user "F.Adhesive")
		(11 "B.Adhes" user "B.Adhesive")
		(13 "F.Paste" user "Package Geometry/Pastemask Top")
		(15 "B.Paste" user "Package Geometry/Pastemask Bottom")
		(5 "F.SilkS" user "Ref Des/Silkscreen Top")
		(7 "B.SilkS" user "Ref Des/Silkscreen Bottom")
		(1 "F.Mask" user "Board Geometry/Soldermask Top")
		(3 "B.Mask" user "Board Geometry/Soldermask Bottom")
		(17 "Dwgs.User" user "User.Drawings")
		(19 "Cmts.User" user "User.Comments")
		(21 "Eco1.User" user "User.Eco1")
		(23 "Eco2.User" user "User.Eco2")
		(25 "Edge.Cuts" user "Board Geometry/Outline")
		(27 "Margin" user)
		(31 "F.CrtYd" user "Package Geometry/Place Bound Top")
		(29 "B.CrtYd" user "Package Geometry/Place Bound Bottom")
		(35 "F.Fab" user "Ref Des/Assembly Top")
		(33 "B.Fab" user "Ref Des/Assembly Bottom")
	)
	(footprint ""
		(layer "F.Cu")
		(at 376.296936 -92.910152 -90)
		(property "Reference" "R483"
			(at 0 0 270)
			(layer "F.SilkS")
			(hide yes)
			(effects
				(font
					(size 1.27 1.27)
				)
			)
		)
		(property "Value" ""
			(at 0 0 270)
			(layer "F.Fab")
			(effects
				(font
					(size 1.27 1.27)
				)
			)
		)
		(duplicate_pad_numbers_are_jumpers no)
		(fp_line
			(start -0.7874 0.4064)
			(end -0.7874 -0.4064)
			(stroke
				(width 0.1524)
				(type default)
			)
			(layer "F.SilkS")
		)
		(fp_line
			(start 0.7874 0.4064)
			(end -0.7874 0.4064)
			(stroke
				(width 0.1524)
				(type default)
			)
			(layer "F.SilkS")
		)
		(fp_line
			(start -0.7874 -0.4064)
			(end 0.7874 -0.4064)
			(stroke
				(width 0.1524)
				(type default)
			)
			(layer "F.SilkS")
		)
		(fp_line
			(start 0.7874 -0.4064)
			(end 0.7874 0.4064)
			(stroke
				(width 0.1524)
				(type default)
			)
			(layer "F.SilkS")
		)
		(fp_line
			(start -0.67945 0.3048)
			(end -0.67945 -0.305054)
			(stroke
				(width 0.1)
				(type default)
			)
			(layer "F.Fab")
		)
		(fp_line
			(start -0.12065 0.3048)
			(end -0.67945 0.3048)
			(stroke
				(width 0.1)
				(type default)
			)
			(layer "F.Fab")
		)
		(fp_line
			(start 0.120396 0.3048)
			(end 0.120396 0.2794)
			(stroke
				(width 0.1)
				(type default)
			)
			(layer "F.Fab")
		)
		(fp_line
			(start 0.67945 0.3048)
			(end 0.120396 0.3048)
			(stroke
				(width 0.1)
				(type default)
			)
			(layer "F.Fab")
		)
		(fp_line
			(start -0.12065 0.2794)
			(end -0.12065 0.3048)
			(stroke
				(width 0.1)
				(type default)
			)
			(layer "F.Fab")
		)
		(fp_line
			(start 0.120396 0.2794)
			(end -0.12065 0.2794)
			(stroke
				(width 0.1)
				(type default)
			)
			(layer "F.Fab")
		)
		(fp_line
			(start -0.12065 -0.2794)
			(end 0.12065 -0.2794)
			(stroke
				(width 0.1)
				(type default)
			)
			(layer "F.Fab")
		)
		(fp_line
			(start 0.12065 -0.2794)
			(end 0.12065 -0.3048)
			(stroke
				(width 0.1)
				(type default)
			)
			(layer "F.Fab")
		)
		(fp_line
			(start 0.12065 -0.3048)
			(end 0.67945 -0.3048)
			(stroke
				(width 0.1)
				(type default)
			)
			(layer "F.Fab")
		)
		(fp_line
			(start 0.67945 -0.3048)
			(end 0.67945 0.3048)
			(stroke
				(width 0.1)
				(type default)
			)
			(layer "F.Fab")
		)
		(fp_line
			(start -0.67945 -0.305054)
			(end -0.12065 -0.305054)
			(stroke
				(width 0.1)
				(type default)
			)
			(layer "F.Fab")
		)
		(fp_line
			(start -0.12065 -0.305054)
			(end -0.12065 -0.2794)
			(stroke
				(width 0.1)
				(type default)
			)
			(layer "F.Fab")
		)
		(pad "1" smd circle
			(at -0.40005 0 270)
			(size 0 0)
			(layers "F.Cu" "F.Mask" "F.Paste")
			(net "JTAG_BMC_DBP_TDO_R")
		)
		(pad "2" smd circle
			(at 0.40005 0 270)
			(size 0 0)
			(layers "F.Cu" "F.Mask" "F.Paste")
			(net "JTAG_BMC_DBP_TDO")
		)
	)
	(footprint ""
		(layer "F.Cu")
		(at 121.708926 -119.810784 -90)
		(property "Reference" "R860"
			(at 0 0 270)
			(layer "F.SilkS")
			(hide yes)
			(effects
				(font
					(size 1.27 1.27)
				)
			)
		)
		(property "Value" ""
			(at 0 0 270)
			(layer "F.Fab")
			(effects
				(font
					(size 1.27 1.27)
				)
			)
		)
		(duplicate_pad_numbers_are_jumpers no)
		(fp_line
			(start -0.7874 0.4064)
			(end -0.7874 -0.4064)
			(stroke
				(width 0.1524)
				(type default)
			)
			(layer "F.SilkS")
		)
		(fp_line
			(start 0.7874 0.4064)
			(end -0.7874 0.4064)
			(stroke
				(width 0.1524)
				(type default)
			)
			(layer "F.SilkS")
		)
		(fp_line
			(start -0.7874 -0.4064)
			(end 0.7874 -0.4064)
			(stroke
				(width 0.1524)
				(type default)
			)
			(layer "F.SilkS")
		)
		(fp_line
			(start 0.7874 -0.4064)
			(end 0.7874 0.4064)
			(stroke
				(width 0.1524)
				(type default)
			)
			(layer "F.SilkS")
		)
		(fp_line
			(start -0.67945 0.3048)
			(end -0.67945 -0.305054)
			(stroke
				(width 0.1)
				(type default)
			)
			(layer "F.Fab")
		)
		(fp_line
			(start -0.12065 0.3048)
			(end -0.67945 0.3048)
			(stroke
				(width 0.1)
				(type default)
			)
			(layer "F.Fab")
		)
		(fp_line
			(start 0.120396 0.3048)
			(end 0.120396 0.2794)
			(stroke
				(width 0.1)
				(type default)
			)
			(layer "F.Fab")
		)
		(fp_line
			(start 0.67945 0.3048)
			(end 0.120396 0.3048)
			(stroke
				(width 0.1)
				(type default)
			)
			(layer "F.Fab")
		)
		(fp_line
			(start -0.12065 0.2794)
			(end -0.12065 0.3048)
			(stroke
				(width 0.1)
				(type default)
			)
			(layer "F.Fab")
		)
		(fp_line
			(start 0.120396 0.2794)
			(end -0.12065 0.2794)
			(stroke
				(width 0.1)
				(type default)
			)
			(layer "F.Fab")
		)
		(fp_line
			(start -0.12065 -0.2794)
			(end 0.12065 -0.2794)
			(stroke
				(width 0.1)
				(type default)
			)
			(layer "F.Fab")
		)
		(fp_line
			(start 0.12065 -0.2794)
			(end 0.12065 -0.3048)
			(stroke
				(width 0.1)
				(type default)
			)
			(layer "F.Fab")
		)
		(fp_line
			(start 0.12065 -0.3048)
			(end 0.67945 -0.3048)
			(stroke
				(width 0.1)
				(type default)
			)
			(layer "F.Fab")
		)
		(fp_line
			(start 0.67945 -0.3048)
			(end 0.67945 0.3048)
			(stroke
				(width 0.1)
				(type default)
			)
			(layer "F.Fab")
		)
		(fp_line
			(start -0.67945 -0.305054)
			(end -0.12065 -0.305054)
			(stroke
				(width 0.1)
				(type default)
			)
			(layer "F.Fab")
		)
		(fp_line
			(start -0.12065 -0.305054)
			(end -0.12065 -0.2794)
			(stroke
				(width 0.1)
				(type default)
			)
			(layer "F.Fab")
		)
		(pad "1" smd circle
			(at -0.40005 0 270)
			(size 0 0)
			(layers "F.Cu" "F.Mask" "F.Paste")
			(net "RST_CPU1_DRAM_CD_N")
		)
		(pad "2" smd circle
			(at 0.40005 0 270)
			(size 0 0)
			(layers "F.Cu" "F.Mask" "F.Paste")
			(net "RST_CPU1_DRAM_CD_PLD_N")
		)
	)
)
